#ISCELL
  pure_quanta quanta_title_block_c *
  *
#CELL
  pure_quanta socket4677_azif0045p001c01cs *
  page19_i1
#ISCELL
  standard offpage *
  page19_i2
#ISCELL
  standard offpage *
  page19_i3
#ISCELL
  standard offpage *
  page19_i4
#ISCELL
  standard offpage *
  page19_i5
